# BASEBOARD_FAB2 (Tioga Pass) — schematic netlist excerpt (pin names and nets, part order shuffled) for the footprints in the layout excerpt that follows; sources: Cadence DE-HDL packaged netlist, KiCad conversion of Wiwynn_Tioga_Pass_MB.brd

C1R24  CAP_A  0.1UF 16V 10% X7R  pkg 0402V  page 139 : A = P0V9_LAN ; B = GND
C3U6  CAP  10UF 16V 10% X6S  pkg 0805  page 216 : A = VR_FET_SW_P12V_STBY_PVDDQ_ABC ; B = GND
C9F22  CAP  470PF 50V 10% X7R  pkg 0402LF  page 141 : A = LED_LAN_1_N ; B = GND

(kicad_pcb
	(version 20260206)
	(generator "pcbnew")
	(generator_version "10.0")
	(general
		(thickness 1.6)
		(legacy_teardrops no)
	)
	(paper "A4")
	(title_block
		(title "Wiwynn_Tioga_Pass_MB.brd")
		(comment 1 "Tioga Pass / footprints 4330-4332 of 4770")
	)
	(layers
		(0 "F.Cu" signal "TOP")
		(4 "In1.Cu" signal "L2GND")
		(6 "In2.Cu" signal "L3")
		(8 "In3.Cu" signal "L4GND")
		(10 "In4.Cu" signal "L5")
		(12 "In5.Cu" signal "L6GND")
		(14 "In6.Cu" signal "L7VCC")
		(16 "In7.Cu" signal "L8VCC")
		(18 "In8.Cu" signal "L9GND")
		(20 "In9.Cu" signal "L10")
		(22 "In10.Cu" signal "L11GND")
		(24 "In11.Cu" signal "L12")
		(26 "In12.Cu" signal "L13GND")
		(2 "B.Cu" signal "BOTTOM")
		(9 "F.Adhes" user "F.Adhesive")
		(11 "B.Adhes" user "B.Adhesive")
		(13 "F.Paste" user "Package Geometry/Pastemask Top")
		(15 "B.Paste" user "Package Geometry/Pastemask Bottom")
		(5 "F.SilkS" user "Ref Des/Silkscreen Top")
		(7 "B.SilkS" user "Ref Des/Silkscreen Bottom")
		(1 "F.Mask" user "Board Geometry/Soldermask Top")
		(3 "B.Mask" user "Board Geometry/Soldermask Bottom")
		(17 "Dwgs.User" user "User.Drawings")
		(19 "Cmts.User" user "User.Comments")
		(21 "Eco1.User" user "User.Eco1")
		(23 "Eco2.User" user "User.Eco2")
		(25 "Edge.Cuts" user "Board Geometry/Outline")
		(27 "Margin" user)
		(31 "F.CrtYd" user "Package Geometry/Place Bound Top")
		(29 "B.CrtYd" user "Package Geometry/Place Bound Bottom")
		(35 "F.Fab" user "Ref Des/Assembly Top")
		(33 "B.Fab" user "Ref Des/Assembly Bottom")
	)
	(footprint ""
		(layer "B.Cu")
		(at 479.95205 4.714748 180)
		(property "Reference" "C9F22"
			(at 0 0 0)
			(layer "B.SilkS")
			(hide yes)
			(effects
				(font
					(size 1.27 1.27)
				)
				(justify mirror)
			)
		)
		(property "Value" ""
			(at 0 0 0)
			(layer "B.Fab")
			(effects
				(font
					(size 1.27 1.27)
				)
				(justify mirror)
			)
		)
		(duplicate_pad_numbers_are_jumpers no)
		(fp_poly
			(pts
				(xy -0.3048 -0.1016) (xy -0.3048 0.9906) (xy 0.3048 0.9906) (xy 0.3048 -0.1016)
			)
			(stroke
				(width 0)
				(type default)
			)
			(fill no)
			(layer "B.CrtYd")
		)
		(fp_line
			(start 0.3048 0.9906)
			(end -0.3048 0.9906)
			(stroke
				(width 0.1)
				(type default)
			)
			(layer "B.Fab")
		)
		(fp_line
			(start 0.3048 -0.1016)
			(end 0.3048 0.9906)
			(stroke
				(width 0.1)
				(type default)
			)
			(layer "B.Fab")
		)
		(fp_line
			(start -0.3048 0.9906)
			(end -0.3048 -0.1016)
			(stroke
				(width 0.1)
				(type default)
			)
			(layer "B.Fab")
		)
		(fp_line
			(start -0.3048 -0.1016)
			(end 0.3048 -0.1016)
			(stroke
				(width 0.1)
				(type default)
			)
			(layer "B.Fab")
		)
		(pad "1" smd rect
			(at 0 0)
			(size 0.508 0.508)
			(layers "B.Cu" "B.Mask" "B.Paste")
			(net "LED_LAN_1_N")
		)
		(pad "2" smd rect
			(at 0 0.889)
			(size 0.508 0.508)
			(layers "B.Cu" "B.Mask" "B.Paste")
			(net "GND")
		)
		(zone
			(layer "B.Cu")
			(hatch none 0.5)
			(connect_pads
				(clearance 0)
			)
			(min_thickness 0.25)
			(keepout
				(tracks not_allowed)
				(vias allowed)
				(pads allowed)
				(copperpour not_allowed)
				(footprints allowed)
			)
			(placement
				(enabled no)
				(sheetname "")
			)
			(fill
				(thermal_gap 0.5)
				(thermal_bridge_width 0.5)
				(island_removal_mode 0)
			)
			(polygon
				(pts
					(xy 479.69805 4.079748) (xy 480.20605 4.079748) (xy 480.20605 4.460748) (xy 479.69805 4.460748)
				)
			)
		)
		(zone
			(layer "B.Cu")
			(hatch none 0.5)
			(connect_pads
				(clearance 0)
			)
			(min_thickness 0.25)
			(keepout
				(tracks allowed)
				(vias not_allowed)
				(pads allowed)
				(copperpour not_allowed)
				(footprints allowed)
			)
			(placement
				(enabled no)
				(sheetname "")
			)
			(fill
				(thermal_gap 0.5)
				(thermal_bridge_width 0.5)
				(island_removal_mode 0)
			)
			(polygon
				(pts
					(xy 479.69805 4.460748) (xy 480.20605 4.460748) (xy 480.20605 4.079748) (xy 479.69805 4.079748)
				)
			)
		)
	)
	(footprint ""
		(layer "B.Cu")
		(at 347.469206 1.043178 -90)
		(property "Reference" "C3U6"
			(at 0 0 90)
			(layer "B.SilkS")
			(hide yes)
			(effects
				(font
					(size 1.27 1.27)
				)
				(justify mirror)
			)
		)
		(property "Value" ""
			(at 0 0 90)
			(layer "B.Fab")
			(effects
				(font
					(size 1.27 1.27)
				)
				(justify mirror)
			)
		)
		(duplicate_pad_numbers_are_jumpers no)
		(fp_rect
			(start 0.7239 1.9939)
			(end -0.7239 -0.2159)
			(stroke
				(width 0)
				(type default)
			)
			(fill no)
			(layer "B.CrtYd")
		)
		(fp_line
			(start -0.7239 1.9939)
			(end -0.7239 -0.2159)
			(stroke
				(width 0.1)
				(type default)
			)
			(layer "B.Fab")
		)
		(fp_line
			(start 0.7239 1.9939)
			(end -0.7239 1.9939)
			(stroke
				(width 0.1)
				(type default)
			)
			(layer "B.Fab")
		)
		(fp_line
			(start -0.7239 -0.2159)
			(end 0.7239 -0.2159)
			(stroke
				(width 0.1)
				(type default)
			)
			(layer "B.Fab")
		)
		(fp_line
			(start 0.7239 -0.2159)
			(end 0.7239 1.9939)
			(stroke
				(width 0.1)
				(type default)
			)
			(layer "B.Fab")
		)
		(pad "1" smd rect
			(at 0 0 90)
			(size 1.27 1.016)
			(layers "B.Cu" "B.Mask" "B.Paste")
			(net "VR_FET_SW_P12V_STBY_PVDDQ_ABC")
		)
		(pad "2" smd rect
			(at 0 1.778 90)
			(size 1.27 1.016)
			(layers "B.Cu" "B.Mask" "B.Paste")
			(net "GND")
		)
		(zone
			(layer "B.Cu")
			(hatch none 0.5)
			(connect_pads
				(clearance 0)
			)
			(min_thickness 0.25)
			(keepout
				(tracks not_allowed)
				(vias allowed)
				(pads allowed)
				(copperpour not_allowed)
				(footprints allowed)
			)
			(placement
				(enabled no)
				(sheetname "")
			)
			(fill
				(thermal_gap 0.5)
				(thermal_bridge_width 0.5)
				(island_removal_mode 0)
			)
			(polygon
				(pts
					(xy 346.199206 1.678178) (xy 346.961206 1.678178) (xy 346.961206 0.408178) (xy 346.199206 0.408178)
				)
			)
		)
	)
	(footprint ""
		(layer "B.Cu")
		(at 479.9838 -42.5958 90)
		(property "Reference" "C1R24"
			(at 0 0 90)
			(layer "B.SilkS")
			(hide yes)
			(effects
				(font
					(size 1.27 1.27)
				)
				(justify mirror)
			)
		)
		(property "Value" ""
			(at 0 0 90)
			(layer "B.Fab")
			(effects
				(font
					(size 1.27 1.27)
				)
				(justify mirror)
			)
		)
		(duplicate_pad_numbers_are_jumpers no)
		(fp_poly
			(pts
				(xy -0.3048 -0.1016) (xy -0.3048 0.9906) (xy 0.3048 0.9906) (xy 0.3048 -0.1016)
			)
			(stroke
				(width 0)
				(type default)
			)
			(fill no)
			(layer "B.CrtYd")
		)
		(fp_line
			(start 0.3048 -0.1016)
			(end 0.3048 0.9906)
			(stroke
				(width 0.1)
				(type default)
			)
			(layer "B.Fab")
		)
		(fp_line
			(start -0.3048 -0.1016)
			(end 0.3048 -0.1016)
			(stroke
				(width 0.1)
				(type default)
			)
			(layer "B.Fab")
		)
		(fp_line
			(start 0.3048 0.9906)
			(end -0.3048 0.9906)
			(stroke
				(width 0.1)
				(type default)
			)
			(layer "B.Fab")
		)
		(fp_line
			(start -0.3048 0.9906)
			(end -0.3048 -0.1016)
			(stroke
				(width 0.1)
				(type default)
			)
			(layer "B.Fab")
		)
		(pad "1" smd rect
			(at 0 0 270)
			(size 0.508 0.508)
			(layers "B.Cu" "B.Mask" "B.Paste")
			(net "P0V9_LAN")
		)
		(pad "2" smd rect
			(at 0 0.889 270)
			(size 0.508 0.508)
			(layers "B.Cu" "B.Mask" "B.Paste")
			(net "GND")
		)
		(zone
			(layer "B.Cu")
			(hatch none 0.5)
			(connect_pads
				(clearance 0)
			)
			(min_thickness 0.25)
			(keepout
				(tracks allowed)
				(vias not_allowed)
				(pads allowed)
				(copperpour not_allowed)
				(footprints allowed)
			)
			(placement
				(enabled no)
				(sheetname "")
			)
			(fill
				(thermal_gap 0.5)
				(thermal_bridge_width 0.5)
				(island_removal_mode 0)
			)
			(polygon
				(pts
					(xy 480.2378 -42.8498) (xy 480.2378 -42.3418) (xy 480.6188 -42.3418) (xy 480.6188 -42.8498)
				)
			)
		)
		(zone
			(layer "B.Cu")
			(hatch none 0.5)
			(connect_pads
				(clearance 0)
			)
			(min_thickness 0.25)
			(keepout
				(tracks not_allowed)
				(vias allowed)
				(pads allowed)
				(copperpour not_allowed)
				(footprints allowed)
			)
			(placement
				(enabled no)
				(sheetname "")
			)
			(fill
				(thermal_gap 0.5)
				(thermal_bridge_width 0.5)
				(island_removal_mode 0)
			)
			(polygon
				(pts
					(xy 480.6188 -42.8498) (xy 480.6188 -42.3418) (xy 480.2378 -42.3418) (xy 480.2378 -42.8498)
				)
			)
		)
	)
)
